# T6G (Grand Teton) — schematic netlist excerpt (pin names and nets, part order shuffled) for the footprints in the layout excerpt that follows; sources: Cadence DE-HDL packaged netlist, KiCad conversion of 04192023_DAF0TMB3IC0_F0TG_MB_C_brd_V02_OCP.brd

R524  Q_RES  1K 1% CHIP  pkg 0402LF  page 54 : A = PVDD18_S5_P1 ; B = JTAG_CPU1_TDI
C438  Q_CAP  4.7UF 6.3V 20% X6S  pkg 0402  page 356 : A = P1V8_CPU1_RT3_1A ; B = GND
PC87  Q_CAP  22UF 4V 20% EMPTY  pkg C0805  page 226 : A = PVDD18_S5_P1 ; B = GND

(kicad_pcb
	(version 20260206)
	(generator "pcbnew")
	(generator_version "10.0")
	(general
		(thickness 1.6)
		(legacy_teardrops no)
	)
	(paper "A4")
	(title_block
		(title "04192023_DAF0TMB3IC0_F0TG_MB_C_brd_V02_OCP.brd")
		(comment 1 "Grand Teton / footprints 6928-6930 of 8354")
	)
	(layers
		(0 "F.Cu" signal "TOP")
		(4 "In1.Cu" signal "GND")
		(6 "In2.Cu" signal "IN1")
		(8 "In3.Cu" signal "GND1")
		(10 "In4.Cu" signal "IN2")
		(12 "In5.Cu" signal "GND2")
		(14 "In6.Cu" signal "IN3")
		(16 "In7.Cu" signal "GND3")
		(18 "In8.Cu" signal "VCC")
		(20 "In9.Cu" signal "VCC1")
		(22 "In10.Cu" signal "GND4")
		(24 "In11.Cu" signal "IN4")
		(26 "In12.Cu" signal "GND5")
		(28 "In13.Cu" signal "IN5")
		(30 "In14.Cu" signal "GND6")
		(32 "In15.Cu" signal "IN6")
		(34 "In16.Cu" signal "GND7")
		(2 "B.Cu" signal "BOTTOM")
		(9 "F.Adhes" user "F.Adhesive")
		(11 "B.Adhes" user "B.Adhesive")
		(13 "F.Paste" user "Package Geometry/Pastemask Top")
		(15 "B.Paste" user "Package Geometry/Pastemask Bottom")
		(5 "F.SilkS" user "Ref Des/Silkscreen Top")
		(7 "B.SilkS" user "Ref Des/Silkscreen Bottom")
		(1 "F.Mask" user "Board Geometry/Soldermask Top")
		(3 "B.Mask" user "Board Geometry/Soldermask Bottom")
		(17 "Dwgs.User" user "User.Drawings")
		(19 "Cmts.User" user "User.Comments")
		(21 "Eco1.User" user "User.Eco1")
		(23 "Eco2.User" user "User.Eco2")
		(25 "Edge.Cuts" user "Board Geometry/Outline")
		(27 "Margin" user)
		(31 "F.CrtYd" user "Package Geometry/Place Bound Top")
		(29 "B.CrtYd" user "Package Geometry/Place Bound Bottom")
		(35 "F.Fab" user "Ref Des/Assembly Top")
		(33 "B.Fab" user "Ref Des/Assembly Bottom")
	)
	(footprint ""
		(layer "B.Cu")
		(at 58.65241 -151.779224 180)
		(property "Reference" "PC87"
			(at 0 0 0)
			(layer "B.SilkS")
			(hide yes)
			(effects
				(font
					(size 1.27 1.27)
				)
				(justify mirror)
			)
		)
		(property "Value" ""
			(at 0 0 0)
			(layer "B.Fab")
			(effects
				(font
					(size 1.27 1.27)
				)
				(justify mirror)
			)
		)
		(duplicate_pad_numbers_are_jumpers no)
		(fp_line
			(start 1.524 0.762)
			(end 1.524 -0.762)
			(stroke
				(width 0.1524)
				(type default)
			)
			(layer "B.SilkS")
		)
		(fp_line
			(start 1.524 -0.762)
			(end -1.524 -0.762)
			(stroke
				(width 0.1524)
				(type default)
			)
			(layer "B.SilkS")
		)
		(fp_line
			(start -1.524 0.762)
			(end 1.524 0.762)
			(stroke
				(width 0.1524)
				(type default)
			)
			(layer "B.SilkS")
		)
		(fp_line
			(start -1.524 -0.762)
			(end -1.524 0.762)
			(stroke
				(width 0.1524)
				(type default)
			)
			(layer "B.SilkS")
		)
		(fp_line
			(start 1.1049 0.724916)
			(end -1.1049 0.724916)
			(stroke
				(width 0.1)
				(type default)
			)
			(layer "B.Fab")
		)
		(fp_line
			(start 1.1049 -0.724916)
			(end 1.1049 0.724916)
			(stroke
				(width 0.1)
				(type default)
			)
			(layer "B.Fab")
		)
		(fp_line
			(start -1.1049 0.724916)
			(end -1.1049 -0.724916)
			(stroke
				(width 0.1)
				(type default)
			)
			(layer "B.Fab")
		)
		(fp_line
			(start -1.1049 -0.724916)
			(end 1.1049 -0.724916)
			(stroke
				(width 0.1)
				(type default)
			)
			(layer "B.Fab")
		)
		(pad "1" smd rect
			(at 0.889 0 180)
			(size 1.016 1.27)
			(layers "B.Cu" "B.Mask" "B.Paste")
			(net "PVDD18_S5_P1")
		)
		(pad "2" smd rect
			(at -0.889 0 180)
			(size 1.016 1.27)
			(layers "B.Cu" "B.Mask" "B.Paste")
			(net "GND")
		)
	)
	(footprint ""
		(layer "B.Cu")
		(at 156.355034 -199.234552 90)
		(property "Reference" "R524"
			(at 0 0 90)
			(layer "B.SilkS")
			(hide yes)
			(effects
				(font
					(size 1.27 1.27)
				)
				(justify mirror)
			)
		)
		(property "Value" ""
			(at 0 0 90)
			(layer "B.Fab")
			(effects
				(font
					(size 1.27 1.27)
				)
				(justify mirror)
			)
		)
		(duplicate_pad_numbers_are_jumpers no)
		(fp_line
			(start 0.7874 -0.4064)
			(end -0.7874 -0.4064)
			(stroke
				(width 0.1524)
				(type default)
			)
			(layer "B.SilkS")
		)
		(fp_line
			(start -0.7874 -0.4064)
			(end -0.7874 0.4064)
			(stroke
				(width 0.1524)
				(type default)
			)
			(layer "B.SilkS")
		)
		(fp_line
			(start 0.7874 0.4064)
			(end 0.7874 -0.4064)
			(stroke
				(width 0.1524)
				(type default)
			)
			(layer "B.SilkS")
		)
		(fp_line
			(start -0.7874 0.4064)
			(end 0.7874 0.4064)
			(stroke
				(width 0.1524)
				(type default)
			)
			(layer "B.SilkS")
		)
		(fp_line
			(start 0.67945 -0.305054)
			(end 0.12065 -0.305054)
			(stroke
				(width 0.1)
				(type default)
			)
			(layer "B.Fab")
		)
		(fp_line
			(start 0.12065 -0.305054)
			(end 0.12065 -0.2794)
			(stroke
				(width 0.1)
				(type default)
			)
			(layer "B.Fab")
		)
		(fp_line
			(start -0.12065 -0.3048)
			(end -0.67945 -0.3048)
			(stroke
				(width 0.1)
				(type default)
			)
			(layer "B.Fab")
		)
		(fp_line
			(start -0.67945 -0.3048)
			(end -0.67945 0.3048)
			(stroke
				(width 0.1)
				(type default)
			)
			(layer "B.Fab")
		)
		(fp_line
			(start 0.12065 -0.2794)
			(end -0.12065 -0.2794)
			(stroke
				(width 0.1)
				(type default)
			)
			(layer "B.Fab")
		)
		(fp_line
			(start -0.12065 -0.2794)
			(end -0.12065 -0.3048)
			(stroke
				(width 0.1)
				(type default)
			)
			(layer "B.Fab")
		)
		(fp_line
			(start 0.12065 0.2794)
			(end 0.12065 0.3048)
			(stroke
				(width 0.1)
				(type default)
			)
			(layer "B.Fab")
		)
		(fp_line
			(start -0.120396 0.2794)
			(end 0.12065 0.2794)
			(stroke
				(width 0.1)
				(type default)
			)
			(layer "B.Fab")
		)
		(fp_line
			(start 0.67945 0.3048)
			(end 0.67945 -0.305054)
			(stroke
				(width 0.1)
				(type default)
			)
			(layer "B.Fab")
		)
		(fp_line
			(start 0.12065 0.3048)
			(end 0.67945 0.3048)
			(stroke
				(width 0.1)
				(type default)
			)
			(layer "B.Fab")
		)
		(fp_line
			(start -0.120396 0.3048)
			(end -0.120396 0.2794)
			(stroke
				(width 0.1)
				(type default)
			)
			(layer "B.Fab")
		)
		(fp_line
			(start -0.67945 0.3048)
			(end -0.120396 0.3048)
			(stroke
				(width 0.1)
				(type default)
			)
			(layer "B.Fab")
		)
		(pad "1" smd circle
			(at 0.40005 0 270)
			(size 0 0)
			(layers "B.Cu" "B.Mask" "B.Paste")
			(net "PVDD18_S5_P1")
		)
		(pad "2" smd circle
			(at -0.40005 0 270)
			(size 0 0)
			(layers "B.Cu" "B.Mask" "B.Paste")
			(net "JTAG_CPU1_TDI")
		)
	)
	(footprint ""
		(layer "B.Cu")
		(at 122.891296 -390.560052 90)
		(property "Reference" "C438"
			(at 0 0 90)
			(layer "B.SilkS")
			(hide yes)
			(effects
				(font
					(size 1.27 1.27)
				)
				(justify mirror)
			)
		)
		(property "Value" ""
			(at 0 0 90)
			(layer "B.Fab")
			(effects
				(font
					(size 1.27 1.27)
				)
				(justify mirror)
			)
		)
		(duplicate_pad_numbers_are_jumpers no)
		(fp_line
			(start 0.7874 -0.4064)
			(end -0.7874 -0.4064)
			(stroke
				(width 0.1524)
				(type default)
			)
			(layer "B.SilkS")
		)
		(fp_line
			(start -0.7874 -0.4064)
			(end -0.7874 0.4064)
			(stroke
				(width 0.1524)
				(type default)
			)
			(layer "B.SilkS")
		)
		(fp_line
			(start 0.7874 0.4064)
			(end 0.7874 -0.4064)
			(stroke
				(width 0.1524)
				(type default)
			)
			(layer "B.SilkS")
		)
		(fp_line
			(start -0.7874 0.4064)
			(end 0.7874 0.4064)
			(stroke
				(width 0.1524)
				(type default)
			)
			(layer "B.SilkS")
		)
		(fp_line
			(start 0.67945 -0.305054)
			(end 0.12065 -0.305054)
			(stroke
				(width 0.1)
				(type default)
			)
			(layer "B.Fab")
		)
		(fp_line
			(start 0.12065 -0.305054)
			(end 0.12065 -0.2794)
			(stroke
				(width 0.1)
				(type default)
			)
			(layer "B.Fab")
		)
		(fp_line
			(start -0.12065 -0.3048)
			(end -0.67945 -0.3048)
			(stroke
				(width 0.1)
				(type default)
			)
			(layer "B.Fab")
		)
		(fp_line
			(start -0.67945 -0.3048)
			(end -0.67945 0.3048)
			(stroke
				(width 0.1)
				(type default)
			)
			(layer "B.Fab")
		)
		(fp_line
			(start 0.12065 -0.2794)
			(end -0.12065 -0.2794)
			(stroke
				(width 0.1)
				(type default)
			)
			(layer "B.Fab")
		)
		(fp_line
			(start -0.12065 -0.2794)
			(end -0.12065 -0.3048)
			(stroke
				(width 0.1)
				(type default)
			)
			(layer "B.Fab")
		)
		(fp_line
			(start 0.12065 0.2794)
			(end 0.12065 0.3048)
			(stroke
				(width 0.1)
				(type default)
			)
			(layer "B.Fab")
		)
		(fp_line
			(start -0.120396 0.2794)
			(end 0.12065 0.2794)
			(stroke
				(width 0.1)
				(type default)
			)
			(layer "B.Fab")
		)
		(fp_line
			(start 0.67945 0.3048)
			(end 0.67945 -0.305054)
			(stroke
				(width 0.1)
				(type default)
			)
			(layer "B.Fab")
		)
		(fp_line
			(start 0.12065 0.3048)
			(end 0.67945 0.3048)
			(stroke
				(width 0.1)
				(type default)
			)
			(layer "B.Fab")
		)
		(fp_line
			(start -0.120396 0.3048)
			(end -0.120396 0.2794)
			(stroke
				(width 0.1)
				(type default)
			)
			(layer "B.Fab")
		)
		(fp_line
			(start -0.67945 0.3048)
			(end -0.120396 0.3048)
			(stroke
				(width 0.1)
				(type default)
			)
			(layer "B.Fab")
		)
		(pad "1" smd circle
			(at 0.40005 0 270)
			(size 0 0)
			(layers "B.Cu" "B.Mask" "B.Paste")
			(net "P1V8_CPU1_RT3_1A")
		)
		(pad "2" smd circle
			(at -0.40005 0 270)
			(size 0 0)
			(layers "B.Cu" "B.Mask" "B.Paste")
			(net "GND")
		)
	)
)
